(kicad_pcb
	(version 20260206)
	(generator "pcbnew")
	(generator_version "10.0")
	(general
		(thickness 1.6)
		(legacy_teardrops no)
	)
	(paper "A4")
	(title_block
		(title "01162023_DA0F0TEBIF0_F0T_Expander_BD_F_brd_V02_OCP.brd")
		(comment 1 "Grand Teton / footprints 548-554 of 9728")
	)
	(layers
		(0 "F.Cu" signal "TOP")
		(4 "In1.Cu" signal "GND")
		(6 "In2.Cu" signal "VCC")
		(8 "In3.Cu" signal "VCC1")
		(10 "In4.Cu" signal "GND1")
		(12 "In5.Cu" signal "IN1")
		(14 "In6.Cu" signal "GND2")
		(16 "In7.Cu" signal "IN2")
		(18 "In8.Cu" signal "GND3")
		(20 "In9.Cu" signal "IN3")
		(22 "In10.Cu" signal "GND4")
		(24 "In11.Cu" signal "IN4")
		(26 "In12.Cu" signal "GND5")
		(28 "In13.Cu" signal "IN5")
		(30 "In14.Cu" signal "GND6")
		(32 "In15.Cu" signal "IN6")
		(34 "In16.Cu" signal "GND7")
		(2 "B.Cu" signal "BOTTOM")
		(9 "F.Adhes" user "F.Adhesive")
		(11 "B.Adhes" user "B.Adhesive")
		(13 "F.Paste" user "Package Geometry/Pastemask Top")
		(15 "B.Paste" user "Package Geometry/Pastemask Bottom")
		(5 "F.SilkS" user "Ref Des/Silkscreen Top")
		(7 "B.SilkS" user "Ref Des/Silkscreen Bottom")
		(1 "F.Mask" user "Board Geometry/Soldermask Top")
		(3 "B.Mask" user "Board Geometry/Soldermask Bottom")
		(17 "Dwgs.User" user "User.Drawings")
		(19 "Cmts.User" user "User.Comments")
		(21 "Eco1.User" user "User.Eco1")
		(23 "Eco2.User" user "User.Eco2")
		(25 "Edge.Cuts" user "Board Geometry/Outline")
		(27 "Margin" user)
		(31 "F.CrtYd" user "Package Geometry/Place Bound Top")
		(29 "B.CrtYd" user "Package Geometry/Place Bound Bottom")
		(35 "F.Fab" user "Ref Des/Assembly Top")
		(33 "B.Fab" user "Ref Des/Assembly Bottom")
	)
	(footprint ""
		(layer "F.Cu")
		(at 375.291096 -255.359662)
		(property "Reference" "C3587"
			(at 0 0 0)
			(layer "F.SilkS")
			(hide yes)
			(effects
				(font
					(size 1.27 1.27)
				)
			)
		)
		(property "Value" ""
			(at 0 0 0)
			(layer "F.Fab")
			(effects
				(font
					(size 1.27 1.27)
				)
			)
		)
		(duplicate_pad_numbers_are_jumpers no)
		(fp_line
			(start -1.2954 -0.5842)
			(end 1.2954 -0.5842)
			(stroke
				(width 0.1524)
				(type default)
			)
			(layer "F.SilkS")
		)
		(fp_line
			(start -1.2954 0.5842)
			(end -1.2954 -0.5842)
			(stroke
				(width 0.1524)
				(type default)
			)
			(layer "F.SilkS")
		)
		(fp_line
			(start 1.2954 -0.5842)
			(end 1.2954 0.5842)
			(stroke
				(width 0.1524)
				(type default)
			)
			(layer "F.SilkS")
		)
		(fp_line
			(start 1.2954 0.5842)
			(end -1.2954 0.5842)
			(stroke
				(width 0.1524)
				(type default)
			)
			(layer "F.SilkS")
		)
		(fp_line
			(start -1.1938 -0.4064)
			(end -0.8636 -0.4064)
			(stroke
				(width 0.1)
				(type default)
			)
			(layer "F.Fab")
		)
		(fp_line
			(start -1.1938 0.4064)
			(end -1.1938 -0.4064)
			(stroke
				(width 0.1)
				(type default)
			)
			(layer "F.Fab")
		)
		(fp_line
			(start -0.8636 -0.4572)
			(end 0.8636 -0.4572)
			(stroke
				(width 0.1)
				(type default)
			)
			(layer "F.Fab")
		)
		(fp_line
			(start -0.8636 -0.4064)
			(end -0.8636 -0.4572)
			(stroke
				(width 0.1)
				(type default)
			)
			(layer "F.Fab")
		)
		(fp_line
			(start -0.8636 0.4064)
			(end -1.1938 0.4064)
			(stroke
				(width 0.1)
				(type default)
			)
			(layer "F.Fab")
		)
		(fp_line
			(start -0.8636 0.4572)
			(end -0.8636 0.4064)
			(stroke
				(width 0.1)
				(type default)
			)
			(layer "F.Fab")
		)
		(fp_line
			(start 0.8636 -0.4572)
			(end 0.8636 -0.4064)
			(stroke
				(width 0.1)
				(type default)
			)
			(layer "F.Fab")
		)
		(fp_line
			(start 0.8636 -0.4064)
			(end 1.1938 -0.4064)
			(stroke
				(width 0.1)
				(type default)
			)
			(layer "F.Fab")
		)
		(fp_line
			(start 0.8636 0.4064)
			(end 0.8636 0.4572)
			(stroke
				(width 0.1)
				(type default)
			)
			(layer "F.Fab")
		)
		(fp_line
			(start 0.8636 0.4572)
			(end -0.8636 0.4572)
			(stroke
				(width 0.1)
				(type default)
			)
			(layer "F.Fab")
		)
		(fp_line
			(start 1.1938 -0.4064)
			(end 1.1938 0.4064)
			(stroke
				(width 0.1)
				(type default)
			)
			(layer "F.Fab")
		)
		(fp_line
			(start 1.1938 0.4064)
			(end 0.8636 0.4064)
			(stroke
				(width 0.1)
				(type default)
			)
			(layer "F.Fab")
		)
		(pad "1" smd rect
			(at -0.7366 0 270)
			(size 0.7112 0.8128)
			(layers "F.Cu" "F.Mask" "F.Paste")
			(net "P1V8_PLL0_PEX3")
		)
		(pad "2" smd rect
			(at 0.7366 0 270)
			(size 0.7112 0.8128)
			(layers "F.Cu" "F.Mask" "F.Paste")
			(net "GND")
		)
	)
	(footprint ""
		(layer "F.Cu")
		(at 34.851848 -350.098614 90)
		(property "Reference" "C2166"
			(at 0 0 90)
			(layer "F.SilkS")
			(hide yes)
			(effects
				(font
					(size 1.27 1.27)
				)
			)
		)
		(property "Value" ""
			(at 0 0 90)
			(layer "F.Fab")
			(effects
				(font
					(size 1.27 1.27)
				)
			)
		)
		(duplicate_pad_numbers_are_jumpers no)
		(fp_line
			(start 0.299974 -0.150114)
			(end 0.299974 0.150114)
			(stroke
				(width 0.1)
				(type default)
			)
			(layer "F.Fab")
		)
		(fp_line
			(start -0.299974 -0.150114)
			(end 0.299974 -0.150114)
			(stroke
				(width 0.1)
				(type default)
			)
			(layer "F.Fab")
		)
		(fp_line
			(start 0.299974 0.150114)
			(end -0.299974 0.150114)
			(stroke
				(width 0.1)
				(type default)
			)
			(layer "F.Fab")
		)
		(fp_line
			(start -0.299974 0.150114)
			(end -0.299974 -0.150114)
			(stroke
				(width 0.1)
				(type default)
			)
			(layer "F.Fab")
		)
		(pad "1" smd rect
			(at -0.2667 0 90)
			(size 0.3048 0.381)
			(layers "F.Cu" "F.Mask" "F.Paste")
			(net "P5E_PEX0_STN4_TX_DP<72>")
		)
		(pad "2" smd rect
			(at 0.2667 0 90)
			(size 0.3048 0.381)
			(layers "F.Cu" "F.Mask" "F.Paste")
			(net "P5E_PEX0_STN4_TX_C_DP<72>")
		)
	)
	(footprint ""
		(layer "F.Cu")
		(at 78.267814 -55.083456)
		(property "Reference" "PC397"
			(at 0 0 0)
			(layer "F.SilkS")
			(hide yes)
			(effects
				(font
					(size 1.27 1.27)
				)
			)
		)
		(property "Value" ""
			(at 0 0 0)
			(layer "F.Fab")
			(effects
				(font
					(size 1.27 1.27)
				)
			)
		)
		(duplicate_pad_numbers_are_jumpers no)
		(fp_line
			(start -0.7874 -0.4064)
			(end 0.7874 -0.4064)
			(stroke
				(width 0.1524)
				(type default)
			)
			(layer "F.SilkS")
		)
		(fp_line
			(start -0.7874 0.4064)
			(end -0.7874 -0.4064)
			(stroke
				(width 0.1524)
				(type default)
			)
			(layer "F.SilkS")
		)
		(fp_line
			(start 0.7874 -0.4064)
			(end 0.7874 0.4064)
			(stroke
				(width 0.1524)
				(type default)
			)
			(layer "F.SilkS")
		)
		(fp_line
			(start 0.7874 0.4064)
			(end -0.7874 0.4064)
			(stroke
				(width 0.1524)
				(type default)
			)
			(layer "F.SilkS")
		)
		(fp_line
			(start -0.67945 -0.305054)
			(end -0.12065 -0.305054)
			(stroke
				(width 0.1)
				(type default)
			)
			(layer "F.Fab")
		)
		(fp_line
			(start -0.67945 0.3048)
			(end -0.67945 -0.305054)
			(stroke
				(width 0.1)
				(type default)
			)
			(layer "F.Fab")
		)
		(fp_line
			(start -0.12065 -0.305054)
			(end -0.12065 -0.2794)
			(stroke
				(width 0.1)
				(type default)
			)
			(layer "F.Fab")
		)
		(fp_line
			(start -0.12065 -0.2794)
			(end 0.12065 -0.2794)
			(stroke
				(width 0.1)
				(type default)
			)
			(layer "F.Fab")
		)
		(fp_line
			(start -0.12065 0.2794)
			(end -0.12065 0.3048)
			(stroke
				(width 0.1)
				(type default)
			)
			(layer "F.Fab")
		)
		(fp_line
			(start -0.12065 0.3048)
			(end -0.67945 0.3048)
			(stroke
				(width 0.1)
				(type default)
			)
			(layer "F.Fab")
		)
		(fp_line
			(start 0.120396 0.2794)
			(end -0.12065 0.2794)
			(stroke
				(width 0.1)
				(type default)
			)
			(layer "F.Fab")
		)
		(fp_line
			(start 0.120396 0.3048)
			(end 0.120396 0.2794)
			(stroke
				(width 0.1)
				(type default)
			)
			(layer "F.Fab")
		)
		(fp_line
			(start 0.12065 -0.3048)
			(end 0.67945 -0.3048)
			(stroke
				(width 0.1)
				(type default)
			)
			(layer "F.Fab")
		)
		(fp_line
			(start 0.12065 -0.2794)
			(end 0.12065 -0.3048)
			(stroke
				(width 0.1)
				(type default)
			)
			(layer "F.Fab")
		)
		(fp_line
			(start 0.67945 -0.3048)
			(end 0.67945 0.3048)
			(stroke
				(width 0.1)
				(type default)
			)
			(layer "F.Fab")
		)
		(fp_line
			(start 0.67945 0.3048)
			(end 0.120396 0.3048)
			(stroke
				(width 0.1)
				(type default)
			)
			(layer "F.Fab")
		)
		(pad "1" smd circle
			(at -0.40005 0)
			(size 0 0)
			(layers "F.Cu" "F.Mask" "F.Paste")
			(net "P5V_AUX")
		)
		(pad "2" smd circle
			(at 0.40005 0)
			(size 0 0)
			(layers "F.Cu" "F.Mask" "F.Paste")
			(net "GND")
		)
	)
	(footprint ""
		(layer "F.Cu")
		(at 162.355276 -35.876738)
		(property "Reference" "R6068"
			(at 0 0 0)
			(layer "F.SilkS")
			(hide yes)
			(effects
				(font
					(size 1.27 1.27)
				)
			)
		)
		(property "Value" ""
			(at 0 0 0)
			(layer "F.Fab")
			(effects
				(font
					(size 1.27 1.27)
				)
			)
		)
		(duplicate_pad_numbers_are_jumpers no)
		(fp_line
			(start -0.7874 -0.4064)
			(end 0.7874 -0.4064)
			(stroke
				(width 0.1524)
				(type default)
			)
			(layer "F.SilkS")
		)
		(fp_line
			(start -0.7874 0.4064)
			(end -0.7874 -0.4064)
			(stroke
				(width 0.1524)
				(type default)
			)
			(layer "F.SilkS")
		)
		(fp_line
			(start 0.7874 -0.4064)
			(end 0.7874 0.4064)
			(stroke
				(width 0.1524)
				(type default)
			)
			(layer "F.SilkS")
		)
		(fp_line
			(start 0.7874 0.4064)
			(end -0.7874 0.4064)
			(stroke
				(width 0.1524)
				(type default)
			)
			(layer "F.SilkS")
		)
		(fp_line
			(start -0.67945 -0.305054)
			(end -0.12065 -0.305054)
			(stroke
				(width 0.1)
				(type default)
			)
			(layer "F.Fab")
		)
		(fp_line
			(start -0.67945 0.3048)
			(end -0.67945 -0.305054)
			(stroke
				(width 0.1)
				(type default)
			)
			(layer "F.Fab")
		)
		(fp_line
			(start -0.12065 -0.305054)
			(end -0.12065 -0.2794)
			(stroke
				(width 0.1)
				(type default)
			)
			(layer "F.Fab")
		)
		(fp_line
			(start -0.12065 -0.2794)
			(end 0.12065 -0.2794)
			(stroke
				(width 0.1)
				(type default)
			)
			(layer "F.Fab")
		)
		(fp_line
			(start -0.12065 0.2794)
			(end -0.12065 0.3048)
			(stroke
				(width 0.1)
				(type default)
			)
			(layer "F.Fab")
		)
		(fp_line
			(start -0.12065 0.3048)
			(end -0.67945 0.3048)
			(stroke
				(width 0.1)
				(type default)
			)
			(layer "F.Fab")
		)
		(fp_line
			(start 0.120396 0.2794)
			(end -0.12065 0.2794)
			(stroke
				(width 0.1)
				(type default)
			)
			(layer "F.Fab")
		)
		(fp_line
			(start 0.120396 0.3048)
			(end 0.120396 0.2794)
			(stroke
				(width 0.1)
				(type default)
			)
			(layer "F.Fab")
		)
		(fp_line
			(start 0.12065 -0.3048)
			(end 0.67945 -0.3048)
			(stroke
				(width 0.1)
				(type default)
			)
			(layer "F.Fab")
		)
		(fp_line
			(start 0.12065 -0.2794)
			(end 0.12065 -0.3048)
			(stroke
				(width 0.1)
				(type default)
			)
			(layer "F.Fab")
		)
		(fp_line
			(start 0.67945 -0.3048)
			(end 0.67945 0.3048)
			(stroke
				(width 0.1)
				(type default)
			)
			(layer "F.Fab")
		)
		(fp_line
			(start 0.67945 0.3048)
			(end 0.120396 0.3048)
			(stroke
				(width 0.1)
				(type default)
			)
			(layer "F.Fab")
		)
		(pad "1" smd circle
			(at -0.40005 0)
			(size 0 0)
			(layers "F.Cu" "F.Mask" "F.Paste")
			(net "P3V3_AUX")
		)
		(pad "2" smd circle
			(at 0.40005 0)
			(size 0 0)
			(layers "F.Cu" "F.Mask" "F.Paste")
			(net "PWRGD_P3V3_SSD6_D")
		)
	)
	(footprint ""
		(layer "F.Cu")
		(at 314.861448 -131.686808 180)
		(property "Reference" "C444"
			(at 0 0 180)
			(layer "F.SilkS")
			(hide yes)
			(effects
				(font
					(size 1.27 1.27)
				)
			)
		)
		(property "Value" ""
			(at 0 0 180)
			(layer "F.Fab")
			(effects
				(font
					(size 1.27 1.27)
				)
			)
		)
		(duplicate_pad_numbers_are_jumpers no)
		(fp_line
			(start 0.299974 0.150114)
			(end -0.299974 0.150114)
			(stroke
				(width 0.1)
				(type default)
			)
			(layer "F.Fab")
		)
		(fp_line
			(start 0.299974 -0.150114)
			(end 0.299974 0.150114)
			(stroke
				(width 0.1)
				(type default)
			)
			(layer "F.Fab")
		)
		(fp_line
			(start -0.299974 0.150114)
			(end -0.299974 -0.150114)
			(stroke
				(width 0.1)
				(type default)
			)
			(layer "F.Fab")
		)
		(fp_line
			(start -0.299974 -0.150114)
			(end 0.299974 -0.150114)
			(stroke
				(width 0.1)
				(type default)
			)
			(layer "F.Fab")
		)
		(pad "1" smd rect
			(at -0.2667 0 180)
			(size 0.3048 0.381)
			(layers "F.Cu" "F.Mask" "F.Paste")
			(net "P5E_PEX2_STN0_TX_DN<5>")
		)
		(pad "2" smd rect
			(at 0.2667 0 180)
			(size 0.3048 0.381)
			(layers "F.Cu" "F.Mask" "F.Paste")
			(net "P5E_PEX2_STN0_TX_C_DN<5>")
		)
	)
	(footprint ""
		(layer "F.Cu")
		(at 188.675518 -69.47916 180)
		(property "Reference" "PU109"
			(at -1.978152 4.13004 90)
			(unlocked yes)
			(layer "F.SilkS")
			(effects
				(font
					(size 0.7874 0.5842)
					(thickness 0.1524)
				)
			)
		)
		(property "Value" ""
			(at 0 0 180)
			(layer "F.Fab")
			(effects
				(font
					(size 1.27 1.27)
				)
			)
		)
		(duplicate_pad_numbers_are_jumpers no)
		(fp_line
			(start 1.239774 1.495298)
			(end -1.239774 1.495298)
			(stroke
				(width 0.1524)
				(type default)
			)
			(layer "F.SilkS")
		)
		(fp_line
			(start 1.239774 -1.495298)
			(end 1.239774 1.495298)
			(stroke
				(width 0.1524)
				(type default)
			)
			(layer "F.SilkS")
		)
		(fp_line
			(start -1.239774 1.495298)
			(end -1.239774 -1.495298)
			(stroke
				(width 0.1524)
				(type default)
			)
			(layer "F.SilkS")
		)
		(fp_line
			(start -1.239774 -1.495298)
			(end 1.239774 -1.495298)
			(stroke
				(width 0.1524)
				(type default)
			)
			(layer "F.SilkS")
		)
		(fp_poly
			(pts
				(xy -1.742186 -1.195832) (xy -2.460752 -0.47752) (xy -1.38303 -0.118364)
			)
			(stroke
				(width 0)
				(type default)
			)
			(fill yes)
			(layer "F.SilkS")
		)
		(fp_line
			(start 0.8001 1.050036)
			(end -0.8001 1.050036)
			(stroke
				(width 0.1)
				(type default)
			)
			(layer "F.Fab")
		)
		(fp_line
			(start 0.8001 -1.050036)
			(end 0.8001 1.050036)
			(stroke
				(width 0.1)
				(type default)
			)
			(layer "F.Fab")
		)
		(fp_line
			(start -0.8001 1.050036)
			(end -0.8001 -1.050036)
			(stroke
				(width 0.1)
				(type default)
			)
			(layer "F.Fab")
		)
		(fp_line
			(start -0.8001 -1.050036)
			(end 0.8001 -1.050036)
			(stroke
				(width 0.1)
				(type default)
			)
			(layer "F.Fab")
		)
		(fp_poly
			(pts
				(xy -2.458974 -0.508) (xy -2.458974 0.508) (xy -1.442974 0)
			)
			(stroke
				(width 0)
				(type default)
			)
			(fill yes)
			(layer "F.Fab")
		)
		(pad "1_2" smd circle
			(at -0.374904 0 270)
			(size 0 0)
			(layers "F.Cu" "F.Mask" "F.Paste")
			(net "P12V_AUX")
		)
		(pad "3" smd rect
			(at -0.499872 0.999998 180)
			(size 0.254 0.7112)
			(layers "F.Cu" "F.Mask" "F.Paste")
			(net "GND")
		)
		(pad "4" smd rect
			(at 0 0.999998 180)
			(size 0.254 0.7112)
			(layers "F.Cu" "F.Mask" "F.Paste")
			(net "P12V_SSD6_CO_ILIMIT")
		)
		(pad "5" smd rect
			(at 0.499872 0.999998 180)
			(size 0.254 0.7112)
			(layers "F.Cu" "F.Mask" "F.Paste")
			(net "P12V_SSD6_CO_MODE")
		)
		(pad "6_7" smd circle
			(at 0.374904 0 90)
			(size 0 0)
			(layers "F.Cu" "F.Mask" "F.Paste")
			(net "P12V_SSD6_R")
		)
		(pad "8" smd rect
			(at 0.499872 -0.999998 180)
			(size 0.254 0.7112)
			(layers "F.Cu" "F.Mask" "F.Paste")
			(net "P12V_SSD6_CO_GATE")
		)
		(pad "9" smd rect
			(at 0 -0.999998 180)
			(size 0.254 0.7112)
			(layers "F.Cu" "F.Mask" "F.Paste")
			(net "P12V_SSD6_CO_EN")
		)
		(pad "10" smd rect
			(at -0.499872 -0.999998 180)
			(size 0.254 0.7112)
			(layers "F.Cu" "F.Mask" "F.Paste")
			(net "P12V_SSD6_CO_DV_DT")
		)
	)
	(footprint ""
		(layer "F.Cu")
		(at 318.32042 -26.666444 -90)
		(property "Reference" "R4075"
			(at 0 0 270)
			(layer "F.SilkS")
			(hide yes)
			(effects
				(font
					(size 1.27 1.27)
				)
			)
		)
		(property "Value" ""
			(at 0 0 270)
			(layer "F.Fab")
			(effects
				(font
					(size 1.27 1.27)
				)
			)
		)
		(duplicate_pad_numbers_are_jumpers no)
		(fp_line
			(start -0.7874 0.4064)
			(end -0.7874 -0.4064)
			(stroke
				(width 0.1524)
				(type default)
			)
			(layer "F.SilkS")
		)
		(fp_line
			(start 0.7874 0.4064)
			(end -0.7874 0.4064)
			(stroke
				(width 0.1524)
				(type default)
			)
			(layer "F.SilkS")
		)
		(fp_line
			(start -0.7874 -0.4064)
			(end 0.7874 -0.4064)
			(stroke
				(width 0.1524)
				(type default)
			)
			(layer "F.SilkS")
		)
		(fp_line
			(start 0.7874 -0.4064)
			(end 0.7874 0.4064)
			(stroke
				(width 0.1524)
				(type default)
			)
			(layer "F.SilkS")
		)
		(fp_line
			(start -0.67945 0.3048)
			(end -0.67945 -0.305054)
			(stroke
				(width 0.1)
				(type default)
			)
			(layer "F.Fab")
		)
		(fp_line
			(start -0.12065 0.3048)
			(end -0.67945 0.3048)
			(stroke
				(width 0.1)
				(type default)
			)
			(layer "F.Fab")
		)
		(fp_line
			(start 0.120396 0.3048)
			(end 0.120396 0.2794)
			(stroke
				(width 0.1)
				(type default)
			)
			(layer "F.Fab")
		)
		(fp_line
			(start 0.67945 0.3048)
			(end 0.120396 0.3048)
			(stroke
				(width 0.1)
				(type default)
			)
			(layer "F.Fab")
		)
		(fp_line
			(start -0.12065 0.2794)
			(end -0.12065 0.3048)
			(stroke
				(width 0.1)
				(type default)
			)
			(layer "F.Fab")
		)
		(fp_line
			(start 0.120396 0.2794)
			(end -0.12065 0.2794)
			(stroke
				(width 0.1)
				(type default)
			)
			(layer "F.Fab")
		)
		(fp_line
			(start -0.12065 -0.2794)
			(end 0.12065 -0.2794)
			(stroke
				(width 0.1)
				(type default)
			)
			(layer "F.Fab")
		)
		(fp_line
			(start 0.12065 -0.2794)
			(end 0.12065 -0.3048)
			(stroke
				(width 0.1)
				(type default)
			)
			(layer "F.Fab")
		)
		(fp_line
			(start 0.12065 -0.3048)
			(end 0.67945 -0.3048)
			(stroke
				(width 0.1)
				(type default)
			)
			(layer "F.Fab")
		)
		(fp_line
			(start 0.67945 -0.3048)
			(end 0.67945 0.3048)
			(stroke
				(width 0.1)
				(type default)
			)
			(layer "F.Fab")
		)
		(fp_line
			(start -0.67945 -0.305054)
			(end -0.12065 -0.305054)
			(stroke
				(width 0.1)
				(type default)
			)
			(layer "F.Fab")
		)
		(fp_line
			(start -0.12065 -0.305054)
			(end -0.12065 -0.2794)
			(stroke
				(width 0.1)
				(type default)
			)
			(layer "F.Fab")
		)
		(pad "1" smd circle
			(at -0.40005 0 270)
			(size 0 0)
			(layers "F.Cu" "F.Mask" "F.Paste")
			(net "PRSNT_SSD11_R_N")
		)
		(pad "2" smd circle
			(at 0.40005 0 270)
			(size 0 0)
			(layers "F.Cu" "F.Mask" "F.Paste")
			(net "PRSNT_SSD11_N")
		)
	)
)
